(kicad_pcb
	(version 20260206)
	(generator "pcbnew")
	(generator_version "10.0")
	(general
		(thickness 1.6)
		(legacy_teardrops no)
	)
	(paper "A4")
	(title_block
		(title "01162023_DA0F0TEBIF0_F0T_Expander_BD_F_brd_V02_OCP.brd")
		(comment 1 "Grand Teton / footprints 3904-3910 of 9728")
	)
	(layers
		(0 "F.Cu" signal "TOP")
		(4 "In1.Cu" signal "GND")
		(6 "In2.Cu" signal "VCC")
		(8 "In3.Cu" signal "VCC1")
		(10 "In4.Cu" signal "GND1")
		(12 "In5.Cu" signal "IN1")
		(14 "In6.Cu" signal "GND2")
		(16 "In7.Cu" signal "IN2")
		(18 "In8.Cu" signal "GND3")
		(20 "In9.Cu" signal "IN3")
		(22 "In10.Cu" signal "GND4")
		(24 "In11.Cu" signal "IN4")
		(26 "In12.Cu" signal "GND5")
		(28 "In13.Cu" signal "IN5")
		(30 "In14.Cu" signal "GND6")
		(32 "In15.Cu" signal "IN6")
		(34 "In16.Cu" signal "GND7")
		(2 "B.Cu" signal "BOTTOM")
		(9 "F.Adhes" user "F.Adhesive")
		(11 "B.Adhes" user "B.Adhesive")
		(13 "F.Paste" user "Package Geometry/Pastemask Top")
		(15 "B.Paste" user "Package Geometry/Pastemask Bottom")
		(5 "F.SilkS" user "Ref Des/Silkscreen Top")
		(7 "B.SilkS" user "Ref Des/Silkscreen Bottom")
		(1 "F.Mask" user "Board Geometry/Soldermask Top")
		(3 "B.Mask" user "Board Geometry/Soldermask Bottom")
		(17 "Dwgs.User" user "User.Drawings")
		(19 "Cmts.User" user "User.Comments")
		(21 "Eco1.User" user "User.Eco1")
		(23 "Eco2.User" user "User.Eco2")
		(25 "Edge.Cuts" user "Board Geometry/Outline")
		(27 "Margin" user)
		(31 "F.CrtYd" user "Package Geometry/Place Bound Top")
		(29 "B.CrtYd" user "Package Geometry/Place Bound Bottom")
		(35 "F.Fab" user "Ref Des/Assembly Top")
		(33 "B.Fab" user "Ref Des/Assembly Bottom")
	)
	(footprint ""
		(layer "F.Cu")
		(at 67.201288 -55.78475 -90)
		(property "Reference" "PD30"
			(at 3.96875 2.176018 90)
			(unlocked yes)
			(layer "F.SilkS")
			(effects
				(font
					(size 0.7874 0.5842)
					(thickness 0.1524)
				)
				(justify left)
			)
		)
		(property "Value" ""
			(at 0 0 270)
			(layer "F.Fab")
			(effects
				(font
					(size 1.27 1.27)
				)
			)
		)
		(duplicate_pad_numbers_are_jumpers no)
		(fp_line
			(start -3.400044 1.459992)
			(end -3.400044 -1.459992)
			(stroke
				(width 0.1524)
				(type default)
			)
			(layer "F.SilkS")
		)
		(fp_line
			(start 4.107942 1.459992)
			(end -3.400044 1.459992)
			(stroke
				(width 0.1524)
				(type default)
			)
			(layer "F.SilkS")
		)
		(fp_line
			(start -3.400044 -1.459992)
			(end 4.107942 -1.459992)
			(stroke
				(width 0.1524)
				(type default)
			)
			(layer "F.SilkS")
		)
		(fp_line
			(start 4.107942 -1.459992)
			(end 4.107942 1.459992)
			(stroke
				(width 0.1524)
				(type default)
			)
			(layer "F.SilkS")
		)
		(fp_poly
			(pts
				(xy 4.107942 -1.459992) (xy 4.107942 1.459992) (xy 3.308096 1.459992) (xy 3.308096 -1.459992)
			)
			(stroke
				(width 0)
				(type default)
			)
			(fill yes)
			(layer "F.SilkS")
		)
		(fp_line
			(start -2.29997 1.459992)
			(end -2.29997 -1.459992)
			(stroke
				(width 0.1)
				(type default)
			)
			(layer "F.Fab")
		)
		(fp_line
			(start 2.29997 1.459992)
			(end -2.29997 1.459992)
			(stroke
				(width 0.1)
				(type default)
			)
			(layer "F.Fab")
		)
		(fp_line
			(start -2.29997 -1.459992)
			(end 2.29997 -1.459992)
			(stroke
				(width 0.1)
				(type default)
			)
			(layer "F.Fab")
		)
		(fp_line
			(start 2.29997 -1.459992)
			(end 2.29997 1.459992)
			(stroke
				(width 0.1)
				(type default)
			)
			(layer "F.Fab")
		)
		(fp_text user "-"
			(at 5.4102 0.29845 90)
			(unlocked yes)
			(layer "F.SilkS")
			(effects
				(font
					(size 1.905 1.4224)
					(thickness 0.1524)
				)
				(justify left)
			)
		)
		(fp_text user "+"
			(at -4.7752 -0.12065 270)
			(unlocked yes)
			(layer "F.SilkS")
			(effects
				(font
					(size 1.905 1.4224)
					(thickness 0.1524)
				)
				(justify left)
			)
		)
		(fp_text user "-"
			(at 5.4102 0.29845 90)
			(unlocked yes)
			(layer "F.Fab")
			(effects
				(font
					(size 1.905 1.4224)
					(thickness 0.1524)
				)
				(justify left)
			)
		)
		(fp_text user "+"
			(at -4.7752 -0.12065 270)
			(unlocked yes)
			(layer "F.Fab")
			(effects
				(font
					(size 1.905 1.4224)
					(thickness 0.1524)
				)
				(justify left)
			)
		)
		(pad "A" smd rect
			(at -1.999996 0)
			(size 1.7018 2.5146)
			(layers "F.Cu" "F.Mask" "F.Paste")
			(net "GND")
		)
		(pad "C" smd rect
			(at 1.999996 0)
			(size 1.7018 2.5146)
			(layers "F.Cu" "F.Mask" "F.Paste")
			(net "P12V_SSD2_R")
		)
	)
	(footprint ""
		(layer "F.Cu")
		(at 381.579882 -229.16896 180)
		(property "Reference" "R907"
			(at 0 0 180)
			(layer "F.SilkS")
			(hide yes)
			(effects
				(font
					(size 1.27 1.27)
				)
			)
		)
		(property "Value" ""
			(at 0 0 180)
			(layer "F.Fab")
			(effects
				(font
					(size 1.27 1.27)
				)
			)
		)
		(duplicate_pad_numbers_are_jumpers no)
		(fp_line
			(start 1.2954 0.5842)
			(end -1.2954 0.5842)
			(stroke
				(width 0.1524)
				(type default)
			)
			(layer "F.SilkS")
		)
		(fp_line
			(start 1.2954 -0.5842)
			(end 1.2954 0.5842)
			(stroke
				(width 0.1524)
				(type default)
			)
			(layer "F.SilkS")
		)
		(fp_line
			(start -1.2954 0.5842)
			(end -1.2954 -0.5842)
			(stroke
				(width 0.1524)
				(type default)
			)
			(layer "F.SilkS")
		)
		(fp_line
			(start -1.2954 -0.5842)
			(end 1.2954 -0.5842)
			(stroke
				(width 0.1524)
				(type default)
			)
			(layer "F.SilkS")
		)
		(fp_line
			(start 1.1938 0.4064)
			(end 0.8636 0.4064)
			(stroke
				(width 0.1)
				(type default)
			)
			(layer "F.Fab")
		)
		(fp_line
			(start 1.1938 -0.406654)
			(end 1.1938 0.4064)
			(stroke
				(width 0.1)
				(type default)
			)
			(layer "F.Fab")
		)
		(fp_line
			(start 0.8636 0.4572)
			(end -0.8636 0.4572)
			(stroke
				(width 0.1)
				(type default)
			)
			(layer "F.Fab")
		)
		(fp_line
			(start 0.8636 0.4064)
			(end 0.8636 0.4572)
			(stroke
				(width 0.1)
				(type default)
			)
			(layer "F.Fab")
		)
		(fp_line
			(start 0.8636 -0.406654)
			(end 1.1938 -0.406654)
			(stroke
				(width 0.1)
				(type default)
			)
			(layer "F.Fab")
		)
		(fp_line
			(start 0.8636 -0.4572)
			(end 0.8636 -0.406654)
			(stroke
				(width 0.1)
				(type default)
			)
			(layer "F.Fab")
		)
		(fp_line
			(start -0.8636 0.4572)
			(end -0.8636 0.4318)
			(stroke
				(width 0.1)
				(type default)
			)
			(layer "F.Fab")
		)
		(fp_line
			(start -0.8636 0.4318)
			(end -0.8636 0.4064)
			(stroke
				(width 0.1)
				(type default)
			)
			(layer "F.Fab")
		)
		(fp_line
			(start -0.8636 0.4064)
			(end -1.1938 0.4064)
			(stroke
				(width 0.1)
				(type default)
			)
			(layer "F.Fab")
		)
		(fp_line
			(start -0.8636 -0.406654)
			(end -0.8636 -0.4572)
			(stroke
				(width 0.1)
				(type default)
			)
			(layer "F.Fab")
		)
		(fp_line
			(start -0.8636 -0.4572)
			(end 0.8636 -0.4572)
			(stroke
				(width 0.1)
				(type default)
			)
			(layer "F.Fab")
		)
		(fp_line
			(start -1.1938 0.4064)
			(end -1.1938 -0.406654)
			(stroke
				(width 0.1)
				(type default)
			)
			(layer "F.Fab")
		)
		(fp_line
			(start -1.1938 -0.406654)
			(end -0.8636 -0.406654)
			(stroke
				(width 0.1)
				(type default)
			)
			(layer "F.Fab")
		)
		(pad "1" smd rect
			(at -0.7366 0 90)
			(size 0.7112 0.8128)
			(layers "F.Cu" "F.Mask" "F.Paste")
			(net "OSC_SDB_OUT")
		)
		(pad "2" smd rect
			(at 0.7366 0 90)
			(size 0.7112 0.8128)
			(layers "F.Cu" "F.Mask" "F.Paste")
			(net "OSC_SDB_IN")
		)
	)
	(footprint ""
		(layer "F.Cu")
		(at 221.105476 -177.390552 180)
		(property "Reference" "C3649"
			(at 0 0 180)
			(layer "F.SilkS")
			(hide yes)
			(effects
				(font
					(size 1.27 1.27)
				)
			)
		)
		(property "Value" ""
			(at 0 0 180)
			(layer "F.Fab")
			(effects
				(font
					(size 1.27 1.27)
				)
			)
		)
		(duplicate_pad_numbers_are_jumpers no)
		(fp_line
			(start 0.7874 0.4064)
			(end -0.7874 0.4064)
			(stroke
				(width 0.1524)
				(type default)
			)
			(layer "F.SilkS")
		)
		(fp_line
			(start 0.7874 -0.4064)
			(end 0.7874 0.4064)
			(stroke
				(width 0.1524)
				(type default)
			)
			(layer "F.SilkS")
		)
		(fp_line
			(start -0.7874 0.4064)
			(end -0.7874 -0.4064)
			(stroke
				(width 0.1524)
				(type default)
			)
			(layer "F.SilkS")
		)
		(fp_line
			(start -0.7874 -0.4064)
			(end 0.7874 -0.4064)
			(stroke
				(width 0.1524)
				(type default)
			)
			(layer "F.SilkS")
		)
		(fp_line
			(start 0.67945 0.3048)
			(end 0.120396 0.3048)
			(stroke
				(width 0.1)
				(type default)
			)
			(layer "F.Fab")
		)
		(fp_line
			(start 0.67945 -0.3048)
			(end 0.67945 0.3048)
			(stroke
				(width 0.1)
				(type default)
			)
			(layer "F.Fab")
		)
		(fp_line
			(start 0.12065 -0.2794)
			(end 0.12065 -0.3048)
			(stroke
				(width 0.1)
				(type default)
			)
			(layer "F.Fab")
		)
		(fp_line
			(start 0.12065 -0.3048)
			(end 0.67945 -0.3048)
			(stroke
				(width 0.1)
				(type default)
			)
			(layer "F.Fab")
		)
		(fp_line
			(start 0.120396 0.3048)
			(end 0.120396 0.2794)
			(stroke
				(width 0.1)
				(type default)
			)
			(layer "F.Fab")
		)
		(fp_line
			(start 0.120396 0.2794)
			(end -0.12065 0.2794)
			(stroke
				(width 0.1)
				(type default)
			)
			(layer "F.Fab")
		)
		(fp_line
			(start -0.12065 0.3048)
			(end -0.67945 0.3048)
			(stroke
				(width 0.1)
				(type default)
			)
			(layer "F.Fab")
		)
		(fp_line
			(start -0.12065 0.2794)
			(end -0.12065 0.3048)
			(stroke
				(width 0.1)
				(type default)
			)
			(layer "F.Fab")
		)
		(fp_line
			(start -0.12065 -0.2794)
			(end 0.12065 -0.2794)
			(stroke
				(width 0.1)
				(type default)
			)
			(layer "F.Fab")
		)
		(fp_line
			(start -0.12065 -0.305054)
			(end -0.12065 -0.2794)
			(stroke
				(width 0.1)
				(type default)
			)
			(layer "F.Fab")
		)
		(fp_line
			(start -0.67945 0.3048)
			(end -0.67945 -0.305054)
			(stroke
				(width 0.1)
				(type default)
			)
			(layer "F.Fab")
		)
		(fp_line
			(start -0.67945 -0.305054)
			(end -0.12065 -0.305054)
			(stroke
				(width 0.1)
				(type default)
			)
			(layer "F.Fab")
		)
		(pad "1" smd circle
			(at -0.40005 0 180)
			(size 0 0)
			(layers "F.Cu" "F.Mask" "F.Paste")
			(net "GND")
		)
		(pad "2" smd circle
			(at 0.40005 0 180)
			(size 0 0)
			(layers "F.Cu" "F.Mask" "F.Paste")
			(net "P3V3_AUX")
		)
	)
	(footprint ""
		(layer "F.Cu")
		(at 77.611478 -71.458074 -90)
		(property "Reference" "PD85"
			(at 4.300474 -2.755392 90)
			(unlocked yes)
			(layer "F.SilkS")
			(effects
				(font
					(size 0.7874 0.5842)
					(thickness 0.1524)
				)
				(justify left)
			)
		)
		(property "Value" ""
			(at 0 0 270)
			(layer "F.Fab")
			(effects
				(font
					(size 1.27 1.27)
				)
			)
		)
		(duplicate_pad_numbers_are_jumpers no)
		(fp_line
			(start -3.656584 1.970024)
			(end 4.240784 1.970024)
			(stroke
				(width 0.1524)
				(type default)
			)
			(layer "F.SilkS")
		)
		(fp_line
			(start 4.240784 1.970024)
			(end 4.240784 -1.970024)
			(stroke
				(width 0.1524)
				(type default)
			)
			(layer "F.SilkS")
		)
		(fp_line
			(start -3.656584 -1.970024)
			(end -3.656584 1.970024)
			(stroke
				(width 0.1524)
				(type default)
			)
			(layer "F.SilkS")
		)
		(fp_line
			(start 4.240784 -1.970024)
			(end -3.656584 -1.970024)
			(stroke
				(width 0.1524)
				(type default)
			)
			(layer "F.SilkS")
		)
		(fp_poly
			(pts
				(xy 3.580384 1.970024) (xy 3.580384 -1.970024) (xy 4.240784 -1.970024) (xy 4.240784 1.970024)
			)
			(stroke
				(width 0)
				(type default)
			)
			(fill yes)
			(layer "F.SilkS")
		)
		(fp_line
			(start -2.3749 1.970024)
			(end 2.3749 1.970024)
			(stroke
				(width 0.1)
				(type default)
			)
			(layer "F.Fab")
		)
		(fp_line
			(start 2.3749 1.970024)
			(end 2.3749 -1.970024)
			(stroke
				(width 0.1)
				(type default)
			)
			(layer "F.Fab")
		)
		(fp_line
			(start -2.3749 -1.970024)
			(end -2.3749 1.970024)
			(stroke
				(width 0.1)
				(type default)
			)
			(layer "F.Fab")
		)
		(fp_line
			(start 2.3749 -1.970024)
			(end -2.3749 -1.970024)
			(stroke
				(width 0.1)
				(type default)
			)
			(layer "F.Fab")
		)
		(fp_text user "+"
			(at -4.9784 -0.23495 270)
			(unlocked yes)
			(layer "F.Fab")
			(effects
				(font
					(size 1.905 1.4224)
					(thickness 0.1524)
				)
				(justify left)
			)
		)
		(fp_text user "-"
			(at 4.1656 -0.23495 270)
			(unlocked yes)
			(layer "F.Fab")
			(effects
				(font
					(size 1.905 1.4224)
					(thickness 0.1524)
				)
				(justify left)
			)
		)
		(pad "A" smd rect
			(at -2.450084 0 270)
			(size 2.159 2.2606)
			(layers "F.Cu" "F.Mask" "F.Paste")
			(net "GND")
		)
		(pad "C" smd rect
			(at 2.450084 0 270)
			(size 2.159 2.2606)
			(layers "F.Cu" "F.Mask" "F.Paste")
			(net "P12V_AUX")
		)
	)
	(footprint ""
		(layer "F.Cu")
		(at 25.611582 -71.458074 -90)
		(property "Reference" "PD84"
			(at 2.370074 -2.736088 90)
			(unlocked yes)
			(layer "F.SilkS")
			(effects
				(font
					(size 0.7874 0.5842)
					(thickness 0.1524)
				)
				(justify left)
			)
		)
		(property "Value" ""
			(at 0 0 270)
			(layer "F.Fab")
			(effects
				(font
					(size 1.27 1.27)
				)
			)
		)
		(duplicate_pad_numbers_are_jumpers no)
		(fp_line
			(start -3.656584 1.970024)
			(end 4.240784 1.970024)
			(stroke
				(width 0.1524)
				(type default)
			)
			(layer "F.SilkS")
		)
		(fp_line
			(start 4.240784 1.970024)
			(end 4.240784 -1.970024)
			(stroke
				(width 0.1524)
				(type default)
			)
			(layer "F.SilkS")
		)
		(fp_line
			(start -3.656584 -1.970024)
			(end -3.656584 1.970024)
			(stroke
				(width 0.1524)
				(type default)
			)
			(layer "F.SilkS")
		)
		(fp_line
			(start 4.240784 -1.970024)
			(end -3.656584 -1.970024)
			(stroke
				(width 0.1524)
				(type default)
			)
			(layer "F.SilkS")
		)
		(fp_poly
			(pts
				(xy 3.580384 1.970024) (xy 3.580384 -1.970024) (xy 4.240784 -1.970024) (xy 4.240784 1.970024)
			)
			(stroke
				(width 0)
				(type default)
			)
			(fill yes)
			(layer "F.SilkS")
		)
		(fp_line
			(start -2.3749 1.970024)
			(end 2.3749 1.970024)
			(stroke
				(width 0.1)
				(type default)
			)
			(layer "F.Fab")
		)
		(fp_line
			(start 2.3749 1.970024)
			(end 2.3749 -1.970024)
			(stroke
				(width 0.1)
				(type default)
			)
			(layer "F.Fab")
		)
		(fp_line
			(start -2.3749 -1.970024)
			(end -2.3749 1.970024)
			(stroke
				(width 0.1)
				(type default)
			)
			(layer "F.Fab")
		)
		(fp_line
			(start 2.3749 -1.970024)
			(end -2.3749 -1.970024)
			(stroke
				(width 0.1)
				(type default)
			)
			(layer "F.Fab")
		)
		(fp_text user "+"
			(at -4.9784 -0.23495 270)
			(unlocked yes)
			(layer "F.Fab")
			(effects
				(font
					(size 1.905 1.4224)
					(thickness 0.1524)
				)
				(justify left)
			)
		)
		(fp_text user "-"
			(at 4.1656 -0.23495 270)
			(unlocked yes)
			(layer "F.Fab")
			(effects
				(font
					(size 1.905 1.4224)
					(thickness 0.1524)
				)
				(justify left)
			)
		)
		(pad "A" smd rect
			(at -2.450084 0 270)
			(size 2.159 2.2606)
			(layers "F.Cu" "F.Mask" "F.Paste")
			(net "GND")
		)
		(pad "C" smd rect
			(at 2.450084 0 270)
			(size 2.159 2.2606)
			(layers "F.Cu" "F.Mask" "F.Paste")
			(net "P12V_AUX")
		)
	)
	(footprint ""
		(layer "F.Cu")
		(at 328.311764 -204.678534 -90)
		(property "Reference" "C2842"
			(at 0 0 270)
			(layer "F.SilkS")
			(hide yes)
			(effects
				(font
					(size 1.27 1.27)
				)
			)
		)
		(property "Value" ""
			(at 0 0 270)
			(layer "F.Fab")
			(effects
				(font
					(size 1.27 1.27)
				)
			)
		)
		(duplicate_pad_numbers_are_jumpers no)
		(fp_line
			(start -0.7874 0.4064)
			(end -0.7874 -0.4064)
			(stroke
				(width 0.1524)
				(type default)
			)
			(layer "F.SilkS")
		)
		(fp_line
			(start 0.7874 0.4064)
			(end -0.7874 0.4064)
			(stroke
				(width 0.1524)
				(type default)
			)
			(layer "F.SilkS")
		)
		(fp_line
			(start -0.7874 -0.4064)
			(end 0.7874 -0.4064)
			(stroke
				(width 0.1524)
				(type default)
			)
			(layer "F.SilkS")
		)
		(fp_line
			(start 0.7874 -0.4064)
			(end 0.7874 0.4064)
			(stroke
				(width 0.1524)
				(type default)
			)
			(layer "F.SilkS")
		)
		(fp_line
			(start -0.67945 0.3048)
			(end -0.67945 -0.305054)
			(stroke
				(width 0.1)
				(type default)
			)
			(layer "F.Fab")
		)
		(fp_line
			(start -0.12065 0.3048)
			(end -0.67945 0.3048)
			(stroke
				(width 0.1)
				(type default)
			)
			(layer "F.Fab")
		)
		(fp_line
			(start 0.120396 0.3048)
			(end 0.120396 0.2794)
			(stroke
				(width 0.1)
				(type default)
			)
			(layer "F.Fab")
		)
		(fp_line
			(start 0.67945 0.3048)
			(end 0.120396 0.3048)
			(stroke
				(width 0.1)
				(type default)
			)
			(layer "F.Fab")
		)
		(fp_line
			(start -0.12065 0.2794)
			(end -0.12065 0.3048)
			(stroke
				(width 0.1)
				(type default)
			)
			(layer "F.Fab")
		)
		(fp_line
			(start 0.120396 0.2794)
			(end -0.12065 0.2794)
			(stroke
				(width 0.1)
				(type default)
			)
			(layer "F.Fab")
		)
		(fp_line
			(start -0.12065 -0.2794)
			(end 0.12065 -0.2794)
			(stroke
				(width 0.1)
				(type default)
			)
			(layer "F.Fab")
		)
		(fp_line
			(start 0.12065 -0.2794)
			(end 0.12065 -0.3048)
			(stroke
				(width 0.1)
				(type default)
			)
			(layer "F.Fab")
		)
		(fp_line
			(start 0.12065 -0.3048)
			(end 0.67945 -0.3048)
			(stroke
				(width 0.1)
				(type default)
			)
			(layer "F.Fab")
		)
		(fp_line
			(start 0.67945 -0.3048)
			(end 0.67945 0.3048)
			(stroke
				(width 0.1)
				(type default)
			)
			(layer "F.Fab")
		)
		(fp_line
			(start -0.67945 -0.305054)
			(end -0.12065 -0.305054)
			(stroke
				(width 0.1)
				(type default)
			)
			(layer "F.Fab")
		)
		(fp_line
			(start -0.12065 -0.305054)
			(end -0.12065 -0.2794)
			(stroke
				(width 0.1)
				(type default)
			)
			(layer "F.Fab")
		)
		(pad "1" smd circle
			(at -0.40005 0 270)
			(size 0 0)
			(layers "F.Cu" "F.Mask" "F.Paste")
			(net "P3V3_AUX")
		)
		(pad "2" smd circle
			(at 0.40005 0 270)
			(size 0 0)
			(layers "F.Cu" "F.Mask" "F.Paste")
			(net "GND")
		)
	)
	(footprint ""
		(layer "F.Cu")
		(at 185.939938 -70.52437 90)
		(property "Reference" "PC854"
			(at 0 0 90)
			(layer "F.SilkS")
			(hide yes)
			(effects
				(font
					(size 1.27 1.27)
				)
			)
		)
		(property "Value" ""
			(at 0 0 90)
			(layer "F.Fab")
			(effects
				(font
					(size 1.27 1.27)
				)
			)
		)
		(duplicate_pad_numbers_are_jumpers no)
		(fp_line
			(start 1.524 -0.762)
			(end 1.524 0.762)
			(stroke
				(width 0.1524)
				(type default)
			)
			(layer "F.SilkS")
		)
		(fp_line
			(start -1.524 -0.762)
			(end 1.524 -0.762)
			(stroke
				(width 0.1524)
				(type default)
			)
			(layer "F.SilkS")
		)
		(fp_line
			(start 1.524 0.762)
			(end -1.524 0.762)
			(stroke
				(width 0.1524)
				(type default)
			)
			(layer "F.SilkS")
		)
		(fp_line
			(start -1.524 0.762)
			(end -1.524 -0.762)
			(stroke
				(width 0.1524)
				(type default)
			)
			(layer "F.SilkS")
		)
		(fp_line
			(start 1.1049 -0.724916)
			(end -1.1049 -0.724916)
			(stroke
				(width 0.1)
				(type default)
			)
			(layer "F.Fab")
		)
		(fp_line
			(start -1.1049 -0.724916)
			(end -1.1049 0.724916)
			(stroke
				(width 0.1)
				(type default)
			)
			(layer "F.Fab")
		)
		(fp_line
			(start 1.1049 0.724916)
			(end 1.1049 -0.724916)
			(stroke
				(width 0.1)
				(type default)
			)
			(layer "F.Fab")
		)
		(fp_line
			(start -1.1049 0.724916)
			(end 1.1049 0.724916)
			(stroke
				(width 0.1)
				(type default)
			)
			(layer "F.Fab")
		)
		(pad "1" smd rect
			(at -0.889 0 270)
			(size 1.016 1.27)
			(layers "F.Cu" "F.Mask" "F.Paste")
			(net "P12V_SSD6_R")
		)
		(pad "2" smd rect
			(at 0.889 0 270)
			(size 1.016 1.27)
			(layers "F.Cu" "F.Mask" "F.Paste")
			(net "GND")
		)
	)
)
